FILE_TYPE = CONNECTIVITY;
{Allegro Design Entry HDL 17.2-2016 S081 (4005846) 1/11/2022}
"PAGE_NUMBER" = 299;
0"NC";
1"P3V3_AUX\g";
2"P3V3_AUX\g";
3"P3V3_AUX\g";
4"P3V3_AUX\g";
5"P3V3_AUX\g";
6"P3V3_AUX\g";
7"P3V3_AUX\g";
8"P3V3_AUX\g";
9"P3V3_AUX\g";
10"P3V3_AUX\g";
11"P3V3_AUX\g";
12"P3V3_AUX\g";
13"P3V3_AUX\g";
14"P3V3_AUX\g";
15"P3V3_AUX\g";
16"P3V3_AUX\g";
17"P3V3_AUX\g";
18"P3V3_AUX\g";
19"P3V3_AUX\g";
20"GND\g";
21"GND\g";
22"GND\g";
23"GND\g";
24"GND\g";
25"GND\g";
26"GND\g";
27"GND\g";
28"GND\g";
29"GND\g";
30"GND\g";
31"GND\g";
32"GND\g";
33"GND\g";
34"GND\g";
35"GND\g";
36"GND\g";
37"GND\g";
38"GND\g";
39"GND\g";
40"GND\g";
41"GND\g";
42"GND\g";
43"GND\g";
44"GND\g";
45"GND\g";
46"GND\g";
47"GPU_FPGA_EROT_FATALERR_ISO_N";
48"GPU_FPGA_EROT_FATALERR";
49"GPU_PRSNT_N";
50"GPU_PRSNT";
51"GPU_WP_HW_CTRL_N";
52"GPU_FPGA_EROT_FATALERR_N";
53"GPU_FPGA_OVERT_N";
54"GPU_FPGA_OVERT";
55"GPU_HMC_PRSNT_N";
56"GPU_BASE_HMC_READY";
57"GPU_FPGA_THERM_OVERT_N";
58"GPU_PRSNT_N_ISO";
59"GPU_BASE_HMC_READY_ISO";
60"GPU_BASE_HMC_READY_N";
61"GPU_FPGA_THERM_OVERT";
62"GPU_HMC_PRSNT";
63"GPU_FPGA_OVERT_ISO_N";
64"GPU_WP_HW_CTRL_ISO";
65"GPU_HMC_PRSNT_ISO_N";
66"GPU_FPGA_THERM_OVERT_ISO_N";
%"UNIVERSAL_POWER"
"1","(-2925,1500)","0","logical_power","I10";
;
HDL_POWER"P3V3_AUX"
CDS_LIB"logical_power";
"A"3;
%"UNIVERSAL_GND"
"1","(-2950,1950)","0","logical_power","I11";
;
HDL_POWER"GND"
CDS_LIB"logical_power";
"A"25;
%"Q_CAP"
"1","(100,1300)","0","pure_quanta","I129";
;
PART_NUMBER"TMP_QCH21006JB10"
TOLERANCE"5%"
MATERIAL"EMPTY"
PACK_TYPE"0402"
VOLTAGE"50V"
VALUE"1000PF"
$LOCATION"C1975"
CDS_LIB"pure_quanta"
CDS_LOCATION"C1975"
$SEC"1"
CDS_SEC"1";
"B"
$PN"2"44;
"A"
$PN"1"65;
%"Q_RES"
"2","(-2975,2600)","0","pure_quanta","I130";
;
PART_NUMBER"CS41002FB09"
WATTAGE"1/16W"
TOLERANCE"1%"
VALUE"100K"
PACK_TYPE"0402LF"
MATERIAL"EMPTY"
$LOCATION"R3429"
CDS_LIB"pure_quanta"
CDS_LOCATION"R3429"
$SEC"1"
CDS_SEC"1";
"A"
$PN"1"19;
"B"
$PN"2"56;
%"Q_RES"
"2","(-2950,2125)","0","pure_quanta","I131";
;
PART_NUMBER"CS35492FB03"
MATERIAL"CHIP"
VALUE"54.9K"
TOLERANCE"1%"
WATTAGE"1/16W"
PACK_TYPE"0402LF"
$LOCATION"R3463"
CDS_LIB"pure_quanta"
CDS_LOCATION"R3463"
$SEC"1"
CDS_SEC"1";
"A"
$PN"1"56;
"B"
$PN"2"25;
%"Q_RES"
"2","(-2925,1250)","0","pure_quanta","I132";
;
PART_NUMBER"CS31002FB08"
MATERIAL"CHIP"
VALUE"10K"
TOLERANCE"1%"
PACK_TYPE"0402LF"
WATTAGE"1/16W"
$LOCATION"R3465"
CDS_LIB"pure_quanta"
CDS_LOCATION"R3465"
$SEC"1"
CDS_SEC"1";
"A"
$PN"1"3;
"B"
$PN"2"55;
%"Q_RES"
"2","(-2900,775)","0","pure_quanta","I133";
;
PART_NUMBER"CS41002FB09"
PACK_TYPE"0402LF"
WATTAGE"1/16W"
MATERIAL"EMPTY"
VALUE"100K"
TOLERANCE"1%"
$LOCATION"R3431"
CDS_LIB"pure_quanta"
CDS_LOCATION"R3431"
$SEC"1"
CDS_SEC"1";
"A"
$PN"1"55;
"B"
$PN"2"24;
%"Q_RES"
"2","(-2975,-375)","0","pure_quanta","I134";
;
PART_NUMBER"CS35492FB03"
PACK_TYPE"0402LF"
WATTAGE"1/16W"
TOLERANCE"1%"
MATERIAL"CHIP"
VALUE"54.9K"
$LOCATION"R3464"
CDS_LIB"pure_quanta"
CDS_LOCATION"R3464"
$SEC"1"
CDS_SEC"1";
"A"
$PN"1"2;
"B"
$PN"2"53;
%"MOSFET_NCH_DUAL"
"1","(3300,4225)","0","pure_quanta","I135";
;
PART_NUMBER"BAM138K0003"
PART_TYPE"SMLF"
VALUE"PJT138K"
MATERIAL"IC"
$LOCATION"Q106"
CDS_LMAN_SYM_OUTLINE"-150,150,150,-150"
NEEDS_NO_SIZE"TRUE"
CDS_LIB"pure_quanta"
CDS_LOCATION"Q106"
$SEC"1"
CDS_SEC"1";
"D1"
$PN"6"64;
"G1"
$PN"2"51;
"S1"
$PN"1"33;
%"UNIVERSAL_POWER"
"1","(2175,4700)","0","logical_power","I138";
;
HDL_POWER"P3V3_AUX"
CDS_LIB"logical_power";
"A"14;
%"UNIVERSAL_GND"
"1","(3350,3850)","0","logical_power","I139";
;
HDL_POWER"GND"
CDS_LIB"logical_power";
"A"33;
%"Q_RES"
"2","(2200,3900)","0","pure_quanta","I144";
;
PART_NUMBER"CS31002FB08"
MATERIAL"CHIP"
WATTAGE"1/16W"
VALUE"10K"
TOLERANCE"1%"
PACK_TYPE"0402LF"
$LOCATION"R3471"
CDS_LIB"pure_quanta"
CDS_LOCATION"R3471"
$SEC"1"
CDS_SEC"1";
"A"
$PN"1"51;
"B"
$PN"2"20;
%"Q_RES"
"2","(2175,4450)","0","pure_quanta","I145";
;
PART_NUMBER"CS31002FB08"
WATTAGE"1/16W"
MATERIAL"EMPTY"
PACK_TYPE"0402LF"
TOLERANCE"1%"
VALUE"10K"
$LOCATION"R3470"
CDS_LIB"pure_quanta"
CDS_LOCATION"R3470"
$SEC"1"
CDS_SEC"1";
"A"
$PN"1"14;
"B"
$PN"2"51;
%"UNIVERSAL_GND"
"1","(2200,3625)","0","logical_power","I146";
;
HDL_POWER"GND"
CDS_LIB"logical_power";
"A"20;
%"Q_RES"
"1","(4200,4175)","1","pure_quanta","I147";
;
PART_NUMBER"CS00002JB13"
MATERIAL"EMPTY"
PACK_TYPE"0402LF"
TOLERANCE"5%"
VALUE"0"
$LOCATION"R3472"
WATTAGE"1/16W"
CDS_LIB"pure_quanta"
CDS_LOCATION"R3472"
$SEC"1"
CDS_SEC"1";
"B"
$PN"2"64;
"A"
$PN"1"34;
%"UNIVERSAL_GND"
"1","(4200,3900)","0","logical_power","I148";
;
CDS_LIB"logical_power"
HDL_POWER"GND";
"A"34;
%"UNIVERSAL_POWER"
"1","(-2975,2850)","0","logical_power","I15";
;
HDL_POWER"P3V3_AUX"
CDS_LIB"logical_power";
"A"19;
%"UNIVERSAL_POWER"
"1","(3900,3575)","0","logical_power","I150";
;
HDL_POWER"P3V3_AUX"
CDS_LIB"logical_power";
"A"8;
%"Q_CAP"
"1","(4800,2650)","0","pure_quanta","I152";
;
PART_NUMBER"TMP_QCH21006JB10"
MATERIAL"EMPTY"
PACK_TYPE"0402"
VALUE"1000PF"
VOLTAGE"50V"
TOLERANCE"5%"
$LOCATION"C1978"
CDS_LIB"pure_quanta"
CDS_LOCATION"C1978"
$SEC"1"
CDS_SEC"1";
"B"
$PN"2"32;
"A"
$PN"1"58;
%"UNIVERSAL_GND"
"1","(4800,2450)","0","logical_power","I153";
;
CDS_LIB"logical_power"
HDL_POWER"GND";
"A"32;
%"Q_RES"
"2","(3900,3275)","0","pure_quanta","I154";
;
PART_NUMBER"CS24702JB10"
TOLERANCE"5%"
VALUE"4.7K"
PACK_TYPE"0402LF"
MATERIAL"CHIP"
WATTAGE"1/16W"
$LOCATION"R3475"
CDS_LIB"pure_quanta"
CDS_LOCATION"R3475"
$SEC"1"
CDS_SEC"1";
"A"
$PN"1"8;
"B"
$PN"2"58;
%"UNIVERSAL_POWER"
"1","(2975,3325)","0","logical_power","I155";
;
HDL_POWER"P3V3_AUX"
CDS_LIB"logical_power";
"A"6;
%"UNIVERSAL_GND"
"1","(3900,2450)","0","logical_power","I156";
;
CDS_LIB"logical_power"
HDL_POWER"GND";
"A"31;
%"MOSFET_NCH_DUAL"
"2","(3850,2825)","0","pure_quanta","I157";
;
PART_NUMBER"BAM138K0003"
PART_TYPE"SMLF"
VALUE"PJT138K"
MATERIAL"IC"
LOCATION"Q107"
CDS_LIB"pure_quanta"
NEEDS_NO_SIZE"TRUE"
CDS_LMAN_SYM_OUTLINE"-150,150,150,-150"
$SEC"2"
CDS_SEC"2";
"S2"
$PN"4"31;
"G2"
$PN"5"50;
"D2"
$PN"3"58;
%"Q_RES"
"2","(2975,3025)","0","pure_quanta","I158";
;
PART_NUMBER"CS24702JB10"
WATTAGE"1/16W"
VALUE"4.7K"
TOLERANCE"5%"
PACK_TYPE"0402LF"
MATERIAL"CHIP"
$LOCATION"R3474"
CDS_LIB"pure_quanta"
CDS_LOCATION"R3474"
$SEC"1"
CDS_SEC"1";
"A"
$PN"1"6;
"B"
$PN"2"50;
%"UNIVERSAL_GND"
"1","(2975,2175)","0","logical_power","I159";
;
HDL_POWER"GND"
CDS_LIB"logical_power";
"A"30;
%"UNIVERSAL_GND"
"1","(-2975,3325)","0","logical_power","I16";
;
CDS_LIB"logical_power"
HDL_POWER"GND";
"A"26;
%"MOSFET_NCH_DUAL"
"1","(2925,2550)","0","pure_quanta","I160";
;
PART_NUMBER"BAM138K0003"
PART_TYPE"SMLF"
VALUE"PJT138K"
MATERIAL"IC"
$LOCATION"Q107"
CDS_LIB"pure_quanta"
NEEDS_NO_SIZE"TRUE"
CDS_LMAN_SYM_OUTLINE"-150,150,150,-150"
CDS_LOCATION"Q107"
$SEC"1"
CDS_SEC"1";
"D1"
$PN"6"50;
"G1"
$PN"2"49;
"S1"
$PN"1"30;
%"UNIVERSAL_POWER"
"1","(1725,3025)","0","logical_power","I161";
;
HDL_POWER"P3V3_AUX"
CDS_LIB"logical_power";
"A"5;
%"Q_RES"
"2","(1750,2300)","0","pure_quanta","I163";
;
PART_NUMBER"CS41002FB09"
MATERIAL"EMPTY"
WATTAGE"1/16W"
TOLERANCE"1%"
VALUE"100K"
PACK_TYPE"0402LF"
$LOCATION"R3473"
CDS_LIB"pure_quanta"
CDS_LOCATION"R3473"
$SEC"1"
CDS_SEC"1";
"A"
$PN"1"49;
"B"
$PN"2"21;
%"UNIVERSAL_GND"
"1","(1750,2100)","0","logical_power","I164";
;
CDS_LIB"logical_power"
HDL_POWER"GND";
"A"21;
%"Q_RES"
"2","(1725,2725)","0","pure_quanta","I166";
;
PART_NUMBER"CS31002FB08"
TOLERANCE"1%"
MATERIAL"CHIP"
WATTAGE"1/16W"
VALUE"10K"
PACK_TYPE"0402LF"
$LOCATION"R3487"
CDS_LIB"pure_quanta"
CDS_LOCATION"R3487"
$SEC"1"
CDS_SEC"1";
"A"
$PN"1"5;
"B"
$PN"2"49;
%"Q_RES"
"2","(-3000,4000)","0","pure_quanta","I167";
;
PART_NUMBER"CS35492FB03"
VALUE"54.9K"
TOLERANCE"1%"
MATERIAL"CHIP"
WATTAGE"1/16W"
PACK_TYPE"0402LF"
$LOCATION"R3498"
CDS_LIB"pure_quanta"
CDS_LOCATION"R3498"
$SEC"1"
CDS_SEC"1";
"A"
$PN"1"13;
"B"
$PN"2"57;
%"MOSFET_NCH_DUAL"
"2","(3825,1200)","0","pure_quanta","I168";
;
PART_NUMBER"BAM138K0003"
MATERIAL"IC"
VALUE"PJT138K"
PART_TYPE"SMLF"
LOCATION"Q108"
CDS_LMAN_SYM_OUTLINE"-150,150,150,-150"
NEEDS_NO_SIZE"TRUE"
CDS_LIB"pure_quanta"
$SEC"2"
CDS_SEC"2";
"S2"
$PN"4"28;
"G2"
$PN"5"48;
"D2"
$PN"3"47;
%"MOSFET_NCH_DUAL"
"1","(2900,925)","0","pure_quanta","I169";
;
PART_NUMBER"BAM138K0003"
PART_TYPE"SMLF"
MATERIAL"IC"
VALUE"PJT138K"
$LOCATION"Q108"
CDS_LMAN_SYM_OUTLINE"-150,150,150,-150"
NEEDS_NO_SIZE"TRUE"
CDS_LIB"pure_quanta"
CDS_LOCATION"Q108"
$SEC"1"
CDS_SEC"1";
"D1"
$PN"6"48;
"G1"
$PN"2"52;
"S1"
$PN"1"29;
%"Q_RES"
"2","(-2975,3525)","0","pure_quanta","I17";
;
PART_NUMBER"CS41002FB09"
TOLERANCE"1%"
VALUE"100K"
MATERIAL"EMPTY"
WATTAGE"1/16W"
PACK_TYPE"0402LF"
$LOCATION"R3428"
CDS_LIB"pure_quanta"
CDS_LOCATION"R3428"
$SEC"1"
CDS_SEC"1";
"A"
$PN"1"57;
"B"
$PN"2"26;
%"Q_CAP"
"1","(4775,1025)","0","pure_quanta","I171";
;
PART_NUMBER"TMP_QCH21006JB10"
VOLTAGE"50V"
PACK_TYPE"0402"
MATERIAL"EMPTY"
TOLERANCE"5%"
VALUE"1000PF"
$LOCATION"C1988"
CDS_LIB"pure_quanta"
CDS_LOCATION"C1988"
$SEC"1"
CDS_SEC"1";
"B"
$PN"2"27;
"A"
$PN"1"47;
%"UNIVERSAL_GND"
"1","(4775,825)","0","logical_power","I172";
;
HDL_POWER"GND"
CDS_LIB"logical_power";
"A"27;
%"UNIVERSAL_POWER"
"1","(3875,1950)","0","logical_power","I173";
;
HDL_POWER"P3V3_AUX"
CDS_LIB"logical_power";
"A"1;
%"Q_RES"
"2","(3875,1650)","0","pure_quanta","I174";
;
PART_NUMBER"CS24702JB10"
VALUE"4.7K"
TOLERANCE"5%"
PACK_TYPE"0402LF"
MATERIAL"CHIP"
WATTAGE"1/16W"
$LOCATION"R3504"
CDS_LIB"pure_quanta"
CDS_LOCATION"R3504"
$SEC"1"
CDS_SEC"1";
"A"
$PN"1"1;
"B"
$PN"2"47;
%"UNIVERSAL_GND"
"1","(3875,825)","0","logical_power","I175";
;
HDL_POWER"GND"
CDS_LIB"logical_power";
"A"28;
%"UNIVERSAL_POWER"
"1","(2950,1700)","0","logical_power","I176";
;
HDL_POWER"P3V3_AUX"
CDS_LIB"logical_power";
"A"4;
%"Q_RES"
"2","(2950,1400)","0","pure_quanta","I177";
;
PART_NUMBER"CS24702JB10"
MATERIAL"CHIP"
TOLERANCE"5%"
VALUE"4.7K"
WATTAGE"1/16W"
PACK_TYPE"0402LF"
$LOCATION"R3503"
CDS_LIB"pure_quanta"
CDS_LOCATION"R3503"
$SEC"1"
CDS_SEC"1";
"A"
$PN"1"4;
"B"
$PN"2"48;
%"UNIVERSAL_GND"
"1","(2950,550)","0","logical_power","I178";
;
CDS_LIB"logical_power"
HDL_POWER"GND";
"A"29;
%"UNIVERSAL_POWER"
"1","(1700,1400)","0","logical_power","I179";
;
HDL_POWER"P3V3_AUX"
CDS_LIB"logical_power";
"A"7;
%"Q_RES"
"2","(1725,675)","0","pure_quanta","I181";
;
PART_NUMBER"CS41002FB09"
PACK_TYPE"0402LF"
VALUE"100K"
TOLERANCE"1%"
MATERIAL"EMPTY"
WATTAGE"1/16W"
$LOCATION"R3502"
CDS_LIB"pure_quanta"
CDS_LOCATION"R3502"
$SEC"1"
CDS_SEC"1";
"A"
$PN"1"52;
"B"
$PN"2"22;
%"UNIVERSAL_GND"
"1","(1725,475)","0","logical_power","I182";
;
HDL_POWER"GND"
CDS_LIB"logical_power";
"A"22;
%"Q_RES"
"2","(1700,1100)","0","pure_quanta","I184";
;
PART_NUMBER"CS35492FB03"
WATTAGE"1/16W"
MATERIAL"CHIP"
TOLERANCE"1%"
VALUE"54.9K"
PACK_TYPE"0402LF"
$LOCATION"R3525"
CDS_LIB"pure_quanta"
CDS_LOCATION"R3525"
$SEC"1"
CDS_SEC"1";
"A"
$PN"1"7;
"B"
$PN"2"52;
%"UNIVERSAL_GND"
"1","(-2950,-1000)","0","logical_power","I2";
;
CDS_LIB"logical_power"
HDL_POWER"GND";
"A"23;
%"UNIVERSAL_POWER"
"1","(-3000,4250)","0","logical_power","I20";
;
HDL_POWER"P3V3_AUX"
CDS_LIB"logical_power";
"A"13;
%"MOSFET_NCH_DUAL"
"1","(-1775,-550)","0","pure_quanta","I21";
;
PART_NUMBER"BAM138K0003"
VALUE"PJT138K"
MATERIAL"IC"
PART_TYPE"SMLF"
$LOCATION"Q104"
CDS_LIB"pure_quanta"
NEEDS_NO_SIZE"TRUE"
CDS_LMAN_SYM_OUTLINE"-150,150,150,-150"
CDS_LOCATION"Q104"
$SEC"1"
CDS_SEC"1";
"D1"
$PN"6"54;
"G1"
$PN"2"53;
"S1"
$PN"1"35;
%"UNIVERSAL_GND"
"1","(-1725,-925)","0","logical_power","I22";
;
HDL_POWER"GND"
CDS_LIB"logical_power";
"A"35;
%"Q_RES"
"2","(-1725,-75)","0","pure_quanta","I23";
;
PART_NUMBER"CS24702JB10"
WATTAGE"1/16W"
MATERIAL"CHIP"
VALUE"4.7K"
TOLERANCE"5%"
PACK_TYPE"0402LF"
$LOCATION"R3435"
CDS_LIB"pure_quanta"
CDS_LOCATION"R3435"
$SEC"1"
CDS_SEC"1";
"A"
$PN"1"15;
"B"
$PN"2"54;
%"UNIVERSAL_POWER"
"1","(-1725,225)","0","logical_power","I24";
;
HDL_POWER"P3V3_AUX"
CDS_LIB"logical_power";
"A"15;
%"UNIVERSAL_GND"
"1","(-800,-650)","0","logical_power","I25";
;
CDS_LIB"logical_power"
HDL_POWER"GND";
"A"36;
%"MOSFET_NCH_DUAL"
"2","(-850,-275)","0","pure_quanta","I26";
;
PART_NUMBER"BAM138K0003"
MATERIAL"IC"
PART_TYPE"SMLF"
VALUE"PJT138K"
LOCATION"Q104"
CDS_LIB"pure_quanta"
NEEDS_NO_SIZE"TRUE"
CDS_LMAN_SYM_OUTLINE"-150,150,150,-150"
$SEC"2"
CDS_SEC"2";
"S2"
$PN"4"36;
"G2"
$PN"5"54;
"D2"
$PN"3"63;
%"Q_RES"
"2","(-800,175)","0","pure_quanta","I27";
;
PART_NUMBER"CS24702JB10"
TOLERANCE"5%"
MATERIAL"CHIP"
WATTAGE"1/16W"
PACK_TYPE"0402LF"
VALUE"4.7K"
$LOCATION"R3437"
CDS_LIB"pure_quanta"
CDS_LOCATION"R3437"
$SEC"1"
CDS_SEC"1";
"A"
$PN"1"16;
"B"
$PN"2"63;
%"UNIVERSAL_POWER"
"1","(-800,475)","0","logical_power","I28";
;
HDL_POWER"P3V3_AUX"
CDS_LIB"logical_power";
"A"16;
%"UNIVERSAL_GND"
"1","(100,-650)","0","logical_power","I29";
;
CDS_LIB"logical_power"
HDL_POWER"GND";
"A"37;
%"Q_RES"
"2","(-2950,-800)","0","pure_quanta","I3";
;
PART_NUMBER"CS41002FB09"
MATERIAL"EMPTY"
WATTAGE"1/16W"
TOLERANCE"1%"
VALUE"100K"
PACK_TYPE"0402LF"
$LOCATION"R3430"
CDS_LIB"pure_quanta"
CDS_LOCATION"R3430"
$SEC"1"
CDS_SEC"1";
"A"
$PN"1"53;
"B"
$PN"2"23;
%"Q_CAP"
"1","(100,-450)","0","pure_quanta","I30";
;
PART_NUMBER"TMP_QCH21006JB10"
MATERIAL"EMPTY"
PACK_TYPE"0402"
VALUE"1000PF"
VOLTAGE"50V"
TOLERANCE"5%"
$LOCATION"C1976"
CDS_LIB"pure_quanta"
CDS_LOCATION"C1976"
$SEC"1"
CDS_SEC"1";
"B"
$PN"2"37;
"A"
$PN"1"63;
%"MOSFET_NCH_DUAL"
"1","(-1800,1025)","0","pure_quanta","I37";
;
PART_NUMBER"BAM138K0003"
PART_TYPE"SMLF"
VALUE"PJT138K"
MATERIAL"IC"
$LOCATION"Q103"
CDS_LIB"pure_quanta"
NEEDS_NO_SIZE"TRUE"
CDS_LMAN_SYM_OUTLINE"-150,150,150,-150"
CDS_LOCATION"Q103"
$SEC"1"
CDS_SEC"1";
"D1"
$PN"6"62;
"G1"
$PN"2"55;
"S1"
$PN"1"41;
%"UNIVERSAL_GND"
"1","(-1750,650)","0","logical_power","I38";
;
CDS_LIB"logical_power"
HDL_POWER"GND";
"A"41;
%"Q_RES"
"2","(-1750,1475)","0","pure_quanta","I39";
;
PART_NUMBER"CS24702JB10"
VALUE"4.7K"
TOLERANCE"5%"
PACK_TYPE"0402LF"
MATERIAL"CHIP"
WATTAGE"1/16W"
$LOCATION"R3434"
CDS_LIB"pure_quanta"
CDS_LOCATION"R3434"
$SEC"1"
CDS_SEC"1";
"A"
$PN"1"10;
"B"
$PN"2"62;
%"MOSFET_NCH_DUAL"
"1","(-1800,2375)","0","pure_quanta","I40";
;
PART_NUMBER"BAM138K0003"
MATERIAL"IC"
PART_TYPE"SMLF"
VALUE"PJT138K"
$LOCATION"Q102"
CDS_LMAN_SYM_OUTLINE"-150,150,150,-150"
NEEDS_NO_SIZE"TRUE"
CDS_LIB"pure_quanta"
CDS_LOCATION"Q102"
$SEC"1"
CDS_SEC"1";
"D1"
$PN"6"60;
"G1"
$PN"2"56;
"S1"
$PN"1"38;
%"UNIVERSAL_POWER"
"1","(-1750,1775)","0","logical_power","I41";
;
HDL_POWER"P3V3_AUX"
CDS_LIB"logical_power";
"A"10;
%"UNIVERSAL_GND"
"1","(-1750,2000)","0","logical_power","I42";
;
HDL_POWER"GND"
CDS_LIB"logical_power";
"A"38;
%"MOSFET_NCH_DUAL"
"2","(-850,1300)","0","pure_quanta","I43";
;
PART_NUMBER"BAM138K0003"
PART_TYPE"SMLF"
MATERIAL"IC"
VALUE"PJT138K"
LOCATION"Q103"
CDS_LIB"pure_quanta"
NEEDS_NO_SIZE"TRUE"
CDS_LMAN_SYM_OUTLINE"-150,150,150,-150"
$SEC"2"
CDS_SEC"2";
"S2"
$PN"4"42;
"G2"
$PN"5"62;
"D2"
$PN"3"65;
%"UNIVERSAL_GND"
"1","(-800,925)","0","logical_power","I44";
;
HDL_POWER"GND"
CDS_LIB"logical_power";
"A"42;
%"Q_RES"
"2","(-800,1725)","0","pure_quanta","I45";
;
PART_NUMBER"CS24702JB10"
VALUE"4.7K"
MATERIAL"CHIP"
PACK_TYPE"0402LF"
WATTAGE"1/16W"
TOLERANCE"5%"
$LOCATION"R3436"
CDS_LIB"pure_quanta"
CDS_LOCATION"R3436"
$SEC"1"
CDS_SEC"1";
"A"
$PN"1"9;
"B"
$PN"2"65;
%"UNIVERSAL_POWER"
"1","(-800,2025)","0","logical_power","I46";
;
HDL_POWER"P3V3_AUX"
CDS_LIB"logical_power";
"A"9;
%"UNIVERSAL_GND"
"1","(-775,2300)","0","logical_power","I47";
;
HDL_POWER"GND"
CDS_LIB"logical_power";
"A"43;
%"MOSFET_NCH_DUAL"
"2","(-825,2675)","0","pure_quanta","I48";
;
PART_NUMBER"BAM138K0003"
MATERIAL"IC"
VALUE"PJT138K"
PART_TYPE"SMLF"
$LOCATION"Q102"
CDS_LIB"pure_quanta"
NEEDS_NO_SIZE"TRUE"
CDS_LMAN_SYM_OUTLINE"-150,150,150,-150"
CDS_LOCATION"Q102"
$SEC"2"
CDS_SEC"2";
"S2"
$PN"4"43;
"G2"
$PN"5"60;
"D2"
$PN"3"59;
%"Q_RES"
"2","(-1775,2825)","0","pure_quanta","I49";
;
PART_NUMBER"CS24702JB10"
PACK_TYPE"0402LF"
MATERIAL"CHIP"
WATTAGE"1/16W"
TOLERANCE"5%"
VALUE"4.7K"
$LOCATION"R3433"
CDS_LIB"pure_quanta"
CDS_LOCATION"R3433"
$SEC"1"
CDS_SEC"1";
"A"
$PN"1"11;
"B"
$PN"2"60;
%"UNIVERSAL_POWER"
"1","(-2975,-75)","0","logical_power","I5";
;
HDL_POWER"P3V3_AUX"
CDS_LIB"logical_power";
"A"2;
%"UNIVERSAL_POWER"
"1","(-1775,3125)","0","logical_power","I50";
;
HDL_POWER"P3V3_AUX"
CDS_LIB"logical_power";
"A"11;
%"UNIVERSAL_GND"
"1","(-1825,3400)","0","logical_power","I51";
;
CDS_LIB"logical_power"
HDL_POWER"GND";
"A"40;
%"MOSFET_NCH_DUAL"
"1","(-1875,3775)","0","pure_quanta","I52";
;
PART_NUMBER"BAM138K0003"
MATERIAL"IC"
PART_TYPE"SMLF"
VALUE"PJT138K"
$LOCATION"Q101"
CDS_LMAN_SYM_OUTLINE"-150,150,150,-150"
NEEDS_NO_SIZE"TRUE"
CDS_LIB"pure_quanta"
CDS_LOCATION"Q101"
$SEC"1"
CDS_SEC"1";
"D1"
$PN"6"61;
"G1"
$PN"2"57;
"S1"
$PN"1"40;
%"Q_RES"
"2","(-1825,4375)","0","pure_quanta","I53";
;
PART_NUMBER"CS24702JB10"
PACK_TYPE"0402LF"
TOLERANCE"5%"
WATTAGE"1/16W"
VALUE"4.7K"
MATERIAL"CHIP"
$LOCATION"R3432"
CDS_LIB"pure_quanta"
CDS_LOCATION"R3432"
$SEC"1"
CDS_SEC"1";
"A"
$PN"1"18;
"B"
$PN"2"61;
%"UNIVERSAL_POWER"
"1","(-1825,4600)","0","logical_power","I54";
;
HDL_POWER"P3V3_AUX"
CDS_LIB"logical_power";
"A"18;
%"Q_RES"
"2","(-775,3100)","0","pure_quanta","I55";
;
PART_NUMBER"CS24702JB10"
MATERIAL"CHIP"
TOLERANCE"5%"
VALUE"4.7K"
PACK_TYPE"0402LF"
WATTAGE"1/16W"
$LOCATION"R3438"
CDS_LIB"pure_quanta"
CDS_LOCATION"R3438"
$SEC"1"
CDS_SEC"1";
"A"
$PN"1"12;
"B"
$PN"2"59;
%"UNIVERSAL_POWER"
"1","(-775,3325)","0","logical_power","I56";
;
HDL_POWER"P3V3_AUX"
CDS_LIB"logical_power";
"A"12;
%"MOSFET_NCH_DUAL"
"2","(-725,4075)","0","pure_quanta","I57";
;
PART_NUMBER"BAM138K0003"
MATERIAL"IC"
VALUE"PJT138K"
PART_TYPE"SMLF"
$LOCATION"Q101"
CDS_LIB"pure_quanta"
NEEDS_NO_SIZE"TRUE"
CDS_LMAN_SYM_OUTLINE"-150,150,150,-150"
CDS_LOCATION"Q101"
$SEC"2"
CDS_SEC"2";
"S2"
$PN"4"39;
"G2"
$PN"5"61;
"D2"
$PN"3"66;
%"UNIVERSAL_GND"
"1","(-675,3700)","0","logical_power","I58";
;
CDS_LIB"logical_power"
HDL_POWER"GND";
"A"39;
%"Q_RES"
"2","(-675,4500)","0","pure_quanta","I59";
;
PART_NUMBER"CS24702JB10"
VALUE"4.7K"
WATTAGE"1/16W"
TOLERANCE"5%"
MATERIAL"CHIP"
PACK_TYPE"0402LF"
$LOCATION"R3439"
CDS_LIB"pure_quanta"
CDS_LOCATION"R3439"
$SEC"1"
CDS_SEC"1";
"A"
$PN"1"17;
"B"
$PN"2"66;
%"UNIVERSAL_GND"
"1","(100,1100)","0","logical_power","I60";
;
HDL_POWER"GND"
CDS_LIB"logical_power";
"A"44;
%"UNIVERSAL_GND"
"1","(50,2450)","0","logical_power","I61";
;
HDL_POWER"GND"
CDS_LIB"logical_power";
"A"45;
%"UNIVERSAL_GND"
"1","(-2900,600)","0","logical_power","I7";
;
CDS_LIB"logical_power"
HDL_POWER"GND";
"A"24;
%"Q_CAP"
"1","(50,2650)","0","pure_quanta","I71";
;
PART_NUMBER"TMP_QCH21006JB10"
VOLTAGE"50V"
TOLERANCE"5%"
MATERIAL"EMPTY"
VALUE"1000PF"
PACK_TYPE"0402"
$LOCATION"C1973"
CDS_LIB"pure_quanta"
CDS_LOCATION"C1973"
$SEC"1"
CDS_SEC"1";
"B"
$PN"2"45;
"A"
$PN"1"59;
%"UNIVERSAL_GND"
"1","(100,3825)","0","logical_power","I73";
;
CDS_LIB"logical_power"
HDL_POWER"GND";
"A"46;
%"Q_CAP"
"1","(100,4025)","0","pure_quanta","I74";
;
PART_NUMBER"TMP_QCH21006JB10"
VALUE"1000PF"
VOLTAGE"50V"
TOLERANCE"5%"
MATERIAL"EMPTY"
PACK_TYPE"0402"
$LOCATION"C1974"
CDS_LIB"pure_quanta"
CDS_LOCATION"C1974"
$SEC"1"
CDS_SEC"1";
"B"
$PN"2"46;
"A"
$PN"1"66;
%"UNIVERSAL_POWER"
"1","(-675,4725)","0","logical_power","I83";
;
HDL_POWER"P3V3_AUX"
CDS_LIB"logical_power";
"A"17;
END.
